FILE_TYPE = CONNECTIVITY;
{Allegro Design Entry HDL 17.2-2016 S081 (4005846) 1/11/2022}
"PAGE_NUMBER" = 42;
0"NC";
1"M_F_CPU1_SA_DQ<31:0>";
2"M_F_CPU1_SB_DQ<31:0>";
3"M_F_CPU1_SA_CB<7:0>";
4"M_F_CPU1_SB_CB<7:0>";
5"M_F_CPU1_SA_DQS_DP<9:0>";
6"M_F_CPU1_SB_DQS_DP<9:0>";
7"M_F_CPU1_SA_CA<6:0>";
8"M_F_CPU1_SB_CA<6:0>";
9"M_F_CPU1_SA_DQS_DN<9:0>";
10"M_F_CPU1_SB_DQS_DN<9:0>";
11"M_F_CPU1_ALERT_N";
12"TP_M_F_CPU1_SA_TEST39F";
13"M_F_CPU1_ALERT_R_N";
14"M_F_CPU1_CLK_DP<0>";
15"M_F_CPU1_CLK_DN<0>";
16"M_F_CPU1_SA_CS_N<0>";
17"M_F_CPU1_SA_CS_N<1>";
18"M_F_CPU1_SA_RSP<0>";
19"M_F_CPU1_SA_PAR";
20"M_F_CPU1_SB_CS_N<0>";
21"M_F_CPU1_SB_CS_N<1>";
22"M_F_CPU1_SB_RSP<0>";
23"M_F_CPU1_SB_PAR";
24"M_F_CPU1_RESET_N";
25"M_F_CPU1_SB_CA<6>";
26"M_F_CPU1_SA_CA<6>";
27"M_F_CPU1_SB_CA<5>";
28"M_F_CPU1_SA_CA<5>";
29"M_F_CPU1_SB_CA<4>";
30"M_F_CPU1_SA_CA<4>";
31"M_F_CPU1_SB_CA<3>";
32"M_F_CPU1_SA_CA<3>";
33"M_F_CPU1_SB_CA<2>";
34"M_F_CPU1_SA_CA<2>";
35"M_F_CPU1_SB_CA<1>";
36"M_F_CPU1_SA_CA<1>";
37"M_F_CPU1_SB_CA<0>";
38"M_F_CPU1_SA_CA<0>";
39"M_F_CPU1_SB_DQS_DP<9>";
40"M_F_CPU1_SB_DQS_DP<1>";
41"M_F_CPU1_SB_DQS_DN<5>";
42"M_F_CPU1_SB_DQS_DP<0>";
43"M_F_CPU1_SB_DQS_DN<4>";
44"M_F_CPU1_SB_DQS_DN<3>";
45"M_F_CPU1_SB_DQS_DN<2>";
46"M_F_CPU1_SB_DQS_DN<1>";
47"M_F_CPU1_SB_DQS_DN<0>";
48"M_F_CPU1_SB_DQS_DP<8>";
49"M_F_CPU1_SB_DQS_DP<7>";
50"M_F_CPU1_SB_DQS_DP<6>";
51"M_F_CPU1_SB_DQS_DP<5>";
52"M_F_CPU1_SB_DQS_DN<9>";
53"M_F_CPU1_SB_DQS_DP<4>";
54"M_F_CPU1_SB_DQS_DN<8>";
55"M_F_CPU1_SB_DQS_DP<3>";
56"M_F_CPU1_SB_DQS_DN<7>";
57"M_F_CPU1_SB_DQS_DP<2>";
58"M_F_CPU1_SB_DQS_DN<6>";
59"M_F_CPU1_SA_DQS_DP<7>";
60"M_F_CPU1_SA_DQS_DP<6>";
61"M_F_CPU1_SA_DQS_DP<5>";
62"M_F_CPU1_SA_DQS_DN<9>";
63"M_F_CPU1_SA_DQS_DP<4>";
64"M_F_CPU1_SA_DQS_DN<8>";
65"M_F_CPU1_SA_DQS_DP<3>";
66"M_F_CPU1_SA_DQS_DN<7>";
67"M_F_CPU1_SA_DQS_DP<2>";
68"M_F_CPU1_SA_DQS_DN<6>";
69"M_F_CPU1_SA_DQS_DP<1>";
70"M_F_CPU1_SA_DQS_DN<5>";
71"M_F_CPU1_SA_DQS_DN<4>";
72"M_F_CPU1_SA_DQS_DN<3>";
73"M_F_CPU1_SA_DQS_DN<2>";
74"M_F_CPU1_SA_DQS_DN<1>";
75"M_F_CPU1_SA_DQS_DN<0>";
76"M_F_CPU1_SA_DQS_DP<9>";
77"M_F_CPU1_SA_DQS_DP<8>";
78"M_F_CPU1_SA_DQS_DP<0>";
79"M_F_CPU1_SB_CB<7>";
80"M_F_CPU1_SB_CB<6>";
81"M_F_CPU1_SB_CB<5>";
82"M_F_CPU1_SB_CB<4>";
83"M_F_CPU1_SB_CB<3>";
84"M_F_CPU1_SB_CB<2>";
85"M_F_CPU1_SB_DQ<29>";
86"M_F_CPU1_SB_DQ<28>";
87"M_F_CPU1_SB_DQ<27>";
88"M_F_CPU1_SB_DQ<26>";
89"M_F_CPU1_SB_DQ<25>";
90"M_F_CPU1_SB_DQ<24>";
91"M_F_CPU1_SA_CB<7>";
92"M_F_CPU1_SB_CB<1>";
93"M_F_CPU1_SA_CB<6>";
94"M_F_CPU1_SB_CB<0>";
95"M_F_CPU1_SB_DQ<31>";
96"M_F_CPU1_SA_CB<5>";
97"M_F_CPU1_SB_DQ<30>";
98"M_F_CPU1_SA_CB<4>";
99"M_F_CPU1_SA_CB<3>";
100"M_F_CPU1_SA_CB<2>";
101"M_F_CPU1_SA_CB<1>";
102"M_F_CPU1_SA_CB<0>";
103"M_F_CPU1_SB_DQ<6>";
104"M_F_CPU1_SB_DQ<18>";
105"M_F_CPU1_SB_DQ<17>";
106"M_F_CPU1_SB_DQ<16>";
107"M_F_CPU1_SB_DQ<15>";
108"M_F_CPU1_SB_DQ<14>";
109"M_F_CPU1_SB_DQ<13>";
110"M_F_CPU1_SB_DQ<12>";
111"M_F_CPU1_SB_DQ<23>";
112"M_F_CPU1_SB_DQ<11>";
113"M_F_CPU1_SB_DQ<22>";
114"M_F_CPU1_SB_DQ<10>";
115"M_F_CPU1_SB_DQ<21>";
116"M_F_CPU1_SB_DQ<20>";
117"M_F_CPU1_SB_DQ<9>";
118"M_F_CPU1_SB_DQ<8>";
119"M_F_CPU1_SB_DQ<7>";
120"M_F_CPU1_SB_DQ<19>";
121"M_F_CPU1_SB_DQ<5>";
122"M_F_CPU1_SB_DQ<4>";
123"M_F_CPU1_SB_DQ<3>";
124"M_F_CPU1_SB_DQ<2>";
125"M_F_CPU1_SA_DQ<19>";
126"M_F_CPU1_SB_DQ<1>";
127"M_F_CPU1_SA_DQ<29>";
128"M_F_CPU1_SB_DQ<0>";
129"M_F_CPU1_SA_DQ<28>";
130"M_F_CPU1_SA_DQ<27>";
131"M_F_CPU1_SA_DQ<26>";
132"M_F_CPU1_SA_DQ<25>";
133"M_F_CPU1_SA_DQ<24>";
134"M_F_CPU1_SA_DQ<23>";
135"M_F_CPU1_SA_DQ<22>";
136"M_F_CPU1_SA_DQ<21>";
137"M_F_CPU1_SA_DQ<20>";
138"M_F_CPU1_SA_DQ<31>";
139"M_F_CPU1_SA_DQ<30>";
140"M_F_CPU1_SA_DQ<7>";
141"M_F_CPU1_SA_DQ<6>";
142"M_F_CPU1_SA_DQ<5>";
143"M_F_CPU1_SA_DQ<4>";
144"M_F_CPU1_SA_DQ<3>";
145"M_F_CPU1_SA_DQ<2>";
146"M_F_CPU1_SA_DQ<1>";
147"M_F_CPU1_SA_DQ<18>";
148"M_F_CPU1_SA_DQ<17>";
149"M_F_CPU1_SA_DQ<16>";
150"M_F_CPU1_SA_DQ<15>";
151"M_F_CPU1_SA_DQ<14>";
152"M_F_CPU1_SA_DQ<13>";
153"M_F_CPU1_SA_DQ<12>";
154"M_F_CPU1_SA_DQ<11>";
155"M_F_CPU1_SA_DQ<10>";
156"M_F_CPU1_SA_DQ<9>";
157"M_F_CPU1_SA_DQ<8>";
158"M_F_CPU1_SA_DQ<0>";
%"GENOA_SP5"
"6","(-4600,3775)","0","pure_quanta","I159";
;
LOCATION"U26"
$SEC"6"
CDS_SEC"6"
PART_TYPE"SMLF"
MATERIAL"IO"
VALUE"SOCKET6096_13568-001"
PART_NUMBER"DGA^6000030"
CDS_LIB"pure_quanta"
CDS_LMAN_SYM_OUTLINE"-650,2525,650,-2525"
NEEDS_NO_SIZE"TRUE";
"TEST39F"
$PN"BF65"12;
"MF1_CLK_L"
$PN"BG67"0;
"MF1_CLK_H"
$PN"BF67"0;
"MF0_CLK_L"
$PN"BD67"15;
"MF0_CLK_H"
$PN"BC67"14;
"MFB_DQS_H9"
$PN"BV67"39;
"MFB_PAR"
$PN"BL67"23;
"MFA_PAR"
$PN"BC66"19;
"MFA0_CS_L0"
$PN"AV67"16;
"MFA_DATA7"
$PN"L66"140;
"MFA_DQS_H7"
$PN"AA66"59;
"MFB_DATA6"
$PN"CG67"103;
"MFB_DATA18"
$PN"CR67"104;
"MFB_DATA29"
$PN"DE66"85;
"MFB_DQS_H1"
$PN"CK67"40;
"MFB_DQS_L5"
$PN"CE66"41;
"MFA_DATA6"
$PN"K67"141;
"MFA_DQS_H6"
$PN"R66"60;
"MFB1_RSP_L"
$PN"BR67"0;
"MFB_DATA5"
$PN"CG66"121;
"MFB_DATA17"
$PN"CR66"105;
"MFB_DATA28"
$PN"DD67"86;
"MFB_DQS_H0"
$PN"CD67"42;
"MFB_DQS_L4"
$PN"BW66"43;
"MFA_DATA5"
$PN"K65"142;
"MFA_DQS_H5"
$PN"J66"61;
"MFA_DQS_L9"
$PN"AM65"62;
"MFB0_RSP_L"
$PN"BP67"22;
"MFB_CHECK7"
$PN"BV65"79;
"MFB_DATA4"
$PN"CF67"122;
"MFB_DATA16"
$PN"CP67"106;
"MFB_DATA27"
$PN"DB65"87;
"MFB_DQS_L3"
$PN"DC67"44;
"MFA_DATA4"
$PN"J67"143;
"MFA_DQS_H4"
$PN"AL67"63;
"MFA_DQS_L8"
$PN"AF65"64;
"MFB_CHECK6"
$PN"BU67"80;
"MFB_DATA3"
$PN"CD65"123;
"MFB_DATA15"
$PN"CP65"107;
"MFB_DATA26"
$PN"DA67"88;
"MFB_DQS_L2"
$PN"CU67"45;
"MFA_DATA3"
$PN"G66"144;
"MFA_DQS_H3"
$PN"AE67"65;
"MFA_DQS_L7"
$PN"Y65"66;
"MFB_CHECK5"
$PN"BU66"81;
"MFB_DATA2"
$PN"CC67"124;
"MFB_DATA14"
$PN"CN67"108;
"MFB_DATA25"
$PN"DA66"89;
"MFB_DQS_L1"
$PN"CL67"46;
"MFA_DATA2"
$PN"F67"145;
"MFA_DATA19"
$PN"W66"125;
"MFA_DQS_H2"
$PN"W67"67;
"MFA_DQS_L6"
$PN"P65"68;
"MFB_CA6"
$PN"BK67"25;
"MFB_CHECK4"
$PN"BT67"82;
"MFB_DATA1"
$PN"CC66"126;
"MFB_DATA13"
$PN"CN66"109;
"MFB_DATA24"
$PN"CY67"90;
"MFB_DQS_L0"
$PN"CE67"47;
"MFA_CA6"
$PN"BB65"26;
"MFA_DATA1"
$PN"F65"146;
"MFA_DATA18"
$PN"V67"147;
"MFA_DATA29"
$PN"AH65"127;
"MFA_DQS_H1"
$PN"N67"69;
"MFA_DQS_L5"
$PN"H65"70;
"MFB_CA5"
$PN"BK65"27;
"MFB_CHECK3"
$PN"CB65"83;
"MFB_DATA0"
$PN"CB67"128;
"MFB_DATA12"
$PN"CM67"110;
"MFB_DATA23"
$PN"CY65"111;
"MFA1_RSP_L"
$PN"BP65"0;
"MFA_CA5"
$PN"BB67"28;
"MFA_DATA0"
$PN"E67"158;
"MFA_DATA17"
$PN"V65"148;
"MFA_DATA28"
$PN"AG67"129;
"MFA_DQS_H0"
$PN"G67"78;
"MFA_DQS_L4"
$PN"AM67"71;
"MFB_CA4"
$PN"BJ66"29;
"MFB_CHECK2"
$PN"CA67"84;
"MFB_DATA11"
$PN"CK65"112;
"MFB_DATA22"
$PN"CW67"113;
"MFA0_RSP_L"
$PN"BN66"18;
"MFA_CA4"
$PN"BA67"30;
"MFA_CHECK7"
$PN"AR66"91;
"MFA_DATA16"
$PN"U67"149;
"MFA_DATA27"
$PN"AE66"130;
"MFA_DQS_L3"
$PN"AF67"72;
"MFB_CA3"
$PN"BJ67"31;
"MFB_CHECK1"
$PN"CA66"92;
"MFB_DATA10"
$PN"CJ67"114;
"MFB_DATA21"
$PN"CW66"115;
"MFA_CA3"
$PN"BA66"32;
"MFA_CHECK6"
$PN"AP67"93;
"MFA_DATA15"
$PN"U66"150;
"MFA_DATA26"
$PN"AD67"131;
"MFA_DQS_L2"
$PN"Y67"73;
"MFB1_CS_L1"
$PN"BM67"0;
"MFB_CA2"
$PN"BH67"33;
"MFB_CHECK0"
$PN"BY67"94;
"MFB_DATA20"
$PN"CV67"116;
"MFB_DATA31"
$PN"DF67"95;
"MFA_CA2"
$PN"AY65"34;
"MFA_CHECK5"
$PN"AP65"96;
"MFA_DATA14"
$PN"T67"151;
"MFA_DATA25"
$PN"AD65"132;
"MFA_DQS_L1"
$PN"P67"74;
"MFB0_CS_L1"
$PN"BN67"21;
"MFB1_CS_L0"
$PN"BL66"0;
"MFB_CA1"
$PN"BH65"35;
"MFB_DATA30"
$PN"DE67"97;
"MFB_DQS_H8"
$PN"DD65"48;
"MFA_CA1"
$PN"AY67"36;
"MFA_CHECK4"
$PN"AN67"98;
"MFA_DATA13"
$PN"T65"152;
"MFA_DATA24"
$PN"AC67"133;
"MFA_DQS_L0"
$PN"H67"75;
"MFB0_CS_L0"
$PN"BM65"20;
"MFB_CA0"
$PN"BG66"37;
"MFB_DQS_H7"
$PN"CV65"49;
"MFA_CA0"
$PN"AW67"38;
"MFA_CHECK3"
$PN"AL66"99;
"MFA_DATA12"
$PN"R67"153;
"MFA_DATA23"
$PN"AC66"134;
"MFB_DQS_H6"
$PN"CM65"50;
"MFA_CHECK2"
$PN"AK67"100;
"MFA_DATA11"
$PN"N66"154;
"MFA_DATA22"
$PN"AB67"135;
"MFB_DQS_H5"
$PN"CF65"51;
"MFB_DQS_L9"
$PN"BW67"52;
"MFA_CHECK1"
$PN"AK65"101;
"MFA_DATA10"
$PN"M67"155;
"MFA_DATA21"
$PN"AB65"136;
"MFB_DATA9"
$PN"CJ66"117;
"MFB_DQS_H4"
$PN"BY65"53;
"MFB_DQS_L8"
$PN"DC66"54;
"MFA1_CS_L1"
$PN"AV65"0;
"MFA_CHECK0"
$PN"AJ67"102;
"MFA_DATA9"
$PN"M65"156;
"MFA_DATA20"
$PN"AA67"137;
"MFA_DATA31"
$PN"AJ66"138;
"MFA_DQS_H9"
$PN"AN66"76;
"MFB_DATA8"
$PN"CH67"118;
"MFB_DQS_H3"
$PN"DB67"55;
"MFB_DQS_L7"
$PN"CU66"56;
"MFA0_CS_L1"
$PN"AW66"17;
"MFA1_CS_L0"
$PN"AU67"0;
"MFA_DATA8"
$PN"L67"157;
"MFA_DATA30"
$PN"AH67"139;
"MFA_DQS_H8"
$PN"AG66"77;
"MFB_DATA7"
$PN"CH65"119;
"MFB_DATA19"
$PN"CT65"120;
"MFB_DQS_H2"
$PN"CT67"57;
"MFB_DQS_L6"
$PN"CL66"58;
"MF_RESET_L"
$PN"AU66"24;
"MF_ALERT_L"
$PN"AT65"13;
%"TAP"
"1","(-3325,6150)","0","mstr_standard","I160";
;
CDS_LIB"mstr_standard"
BODY_TYPE"PLUMBING"
HDL_TAP"TRUE";
"B \NAC \NWC"1;
"S \NAC"
BN"0"158;
%"TAP"
"1","(-3325,6100)","0","mstr_standard","I163";
;
CDS_LIB"mstr_standard"
BODY_TYPE"PLUMBING"
HDL_TAP"TRUE";
"B \NAC \NWC"1;
"S \NAC"
BN"1"146;
%"TAP"
"1","(-3325,6050)","0","mstr_standard","I164";
;
CDS_LIB"mstr_standard"
BODY_TYPE"PLUMBING"
HDL_TAP"TRUE";
"B \NAC \NWC"1;
"S \NAC"
BN"2"145;
%"TAP"
"1","(-3325,5900)","0","mstr_standard","I165";
;
CDS_LIB"mstr_standard"
BODY_TYPE"PLUMBING"
HDL_TAP"TRUE";
"B \NAC \NWC"1;
"S \NAC"
BN"5"142;
%"TAP"
"1","(-3325,6000)","0","mstr_standard","I166";
;
CDS_LIB"mstr_standard"
BODY_TYPE"PLUMBING"
HDL_TAP"TRUE";
"B \NAC \NWC"1;
"S \NAC"
BN"3"144;
%"TAP"
"1","(-3325,5950)","0","mstr_standard","I167";
;
CDS_LIB"mstr_standard"
BODY_TYPE"PLUMBING"
HDL_TAP"TRUE";
"B \NAC \NWC"1;
"S \NAC"
BN"4"143;
%"TAP"
"1","(-3325,5850)","0","mstr_standard","I168";
;
CDS_LIB"mstr_standard"
BODY_TYPE"PLUMBING"
HDL_TAP"TRUE";
"B \NAC \NWC"1;
"S \NAC"
BN"6"141;
%"TAP"
"1","(-3325,5800)","0","mstr_standard","I169";
;
CDS_LIB"mstr_standard"
BODY_TYPE"PLUMBING"
HDL_TAP"TRUE";
"B \NAC \NWC"1;
"S \NAC"
BN"7"140;
%"TAP"
"1","(-3325,5700)","0","mstr_standard","I170";
;
CDS_LIB"mstr_standard"
BODY_TYPE"PLUMBING"
HDL_TAP"TRUE";
"B \NAC \NWC"1;
"S \NAC"
BN"8"157;
%"TAP"
"1","(-3325,5650)","0","mstr_standard","I171";
;
CDS_LIB"mstr_standard"
BODY_TYPE"PLUMBING"
HDL_TAP"TRUE";
"B \NAC \NWC"1;
"S \NAC"
BN"9"156;
%"TAP"
"1","(-3325,5550)","0","mstr_standard","I172";
;
CDS_LIB"mstr_standard"
BODY_TYPE"PLUMBING"
HDL_TAP"TRUE";
"B \NAC \NWC"1;
"S \NAC"
BN"11"154;
%"TAP"
"1","(-3325,5600)","0","mstr_standard","I173";
;
CDS_LIB"mstr_standard"
BODY_TYPE"PLUMBING"
HDL_TAP"TRUE";
"B \NAC \NWC"1;
"S \NAC"
BN"10"155;
%"TAP"
"1","(-3325,5450)","0","mstr_standard","I174";
;
CDS_LIB"mstr_standard"
BODY_TYPE"PLUMBING"
HDL_TAP"TRUE";
"B \NAC \NWC"1;
"S \NAC"
BN"13"152;
%"TAP"
"1","(-3325,5500)","0","mstr_standard","I175";
;
CDS_LIB"mstr_standard"
BODY_TYPE"PLUMBING"
HDL_TAP"TRUE";
"B \NAC \NWC"1;
"S \NAC"
BN"12"153;
%"TAP"
"1","(-3325,5400)","0","mstr_standard","I176";
;
CDS_LIB"mstr_standard"
BODY_TYPE"PLUMBING"
HDL_TAP"TRUE";
"B \NAC \NWC"1;
"S \NAC"
BN"14"151;
%"TAP"
"1","(-3325,5350)","0","mstr_standard","I177";
;
CDS_LIB"mstr_standard"
BODY_TYPE"PLUMBING"
HDL_TAP"TRUE";
"B \NAC \NWC"1;
"S \NAC"
BN"15"150;
%"TAP"
"1","(-3325,5250)","0","mstr_standard","I178";
;
CDS_LIB"mstr_standard"
BODY_TYPE"PLUMBING"
HDL_TAP"TRUE";
"B \NAC \NWC"1;
"S \NAC"
BN"16"149;
%"TAP"
"1","(-3325,5200)","0","mstr_standard","I179";
;
CDS_LIB"mstr_standard"
BODY_TYPE"PLUMBING"
HDL_TAP"TRUE";
"B \NAC \NWC"1;
"S \NAC"
BN"17"148;
%"TAP"
"1","(-3325,5150)","0","mstr_standard","I180";
;
CDS_LIB"mstr_standard"
BODY_TYPE"PLUMBING"
HDL_TAP"TRUE";
"B \NAC \NWC"1;
"S \NAC"
BN"18"147;
%"TAP"
"1","(-3325,5100)","0","mstr_standard","I181";
;
CDS_LIB"mstr_standard"
BODY_TYPE"PLUMBING"
HDL_TAP"TRUE";
"B \NAC \NWC"1;
"S \NAC"
BN"19"125;
%"TAP"
"1","(-3325,5050)","0","mstr_standard","I182";
;
CDS_LIB"mstr_standard"
BODY_TYPE"PLUMBING"
HDL_TAP"TRUE";
"B \NAC \NWC"1;
"S \NAC"
BN"20"137;
%"TAP"
"1","(-3325,5000)","0","mstr_standard","I183";
;
CDS_LIB"mstr_standard"
BODY_TYPE"PLUMBING"
HDL_TAP"TRUE";
"B \NAC \NWC"1;
"S \NAC"
BN"21"136;
%"TAP"
"1","(-3325,4900)","0","mstr_standard","I184";
;
CDS_LIB"mstr_standard"
BODY_TYPE"PLUMBING"
HDL_TAP"TRUE";
"B \NAC \NWC"1;
"S \NAC"
BN"23"134;
%"TAP"
"1","(-3325,4950)","0","mstr_standard","I185";
;
CDS_LIB"mstr_standard"
BODY_TYPE"PLUMBING"
HDL_TAP"TRUE";
"B \NAC \NWC"1;
"S \NAC"
BN"22"135;
%"TAP"
"1","(-3325,4750)","0","mstr_standard","I186";
;
CDS_LIB"mstr_standard"
BODY_TYPE"PLUMBING"
HDL_TAP"TRUE";
"B \NAC \NWC"1;
"S \NAC"
BN"25"132;
%"TAP"
"1","(-3325,4800)","0","mstr_standard","I187";
;
CDS_LIB"mstr_standard"
BODY_TYPE"PLUMBING"
HDL_TAP"TRUE";
"B \NAC \NWC"1;
"S \NAC"
BN"24"133;
%"TAP"
"1","(-3325,4700)","0","mstr_standard","I188";
;
CDS_LIB"mstr_standard"
BODY_TYPE"PLUMBING"
HDL_TAP"TRUE";
"B \NAC \NWC"1;
"S \NAC"
BN"26"131;
%"TAP"
"1","(-3325,4650)","0","mstr_standard","I189";
;
CDS_LIB"mstr_standard"
BODY_TYPE"PLUMBING"
HDL_TAP"TRUE";
"B \NAC \NWC"1;
"S \NAC"
BN"27"130;
%"TAP"
"1","(-3325,4600)","0","mstr_standard","I190";
;
CDS_LIB"mstr_standard"
BODY_TYPE"PLUMBING"
HDL_TAP"TRUE";
"B \NAC \NWC"1;
"S \NAC"
BN"28"129;
%"TAP"
"1","(-3325,4500)","0","mstr_standard","I191";
;
CDS_LIB"mstr_standard"
BODY_TYPE"PLUMBING"
HDL_TAP"TRUE";
"B \NAC \NWC"1;
"S \NAC"
BN"30"139;
%"TAP"
"1","(-3325,4550)","0","mstr_standard","I192";
;
CDS_LIB"mstr_standard"
BODY_TYPE"PLUMBING"
HDL_TAP"TRUE";
"B \NAC \NWC"1;
"S \NAC"
BN"29"127;
%"TAP"
"1","(-3325,4450)","0","mstr_standard","I193";
;
CDS_LIB"mstr_standard"
BODY_TYPE"PLUMBING"
HDL_TAP"TRUE";
"B \NAC \NWC"1;
"S \NAC"
BN"31"138;
%"TAP"
"1","(-3325,4350)","0","mstr_standard","I194";
;
CDS_LIB"mstr_standard"
BODY_TYPE"PLUMBING"
HDL_TAP"TRUE";
"B \NAC \NWC"2;
"S \NAC"
BN"0"128;
%"TAP"
"1","(-3325,4300)","0","mstr_standard","I195";
;
CDS_LIB"mstr_standard"
BODY_TYPE"PLUMBING"
HDL_TAP"TRUE";
"B \NAC \NWC"2;
"S \NAC"
BN"1"126;
%"TAP"
"1","(-3325,4250)","0","mstr_standard","I196";
;
CDS_LIB"mstr_standard"
BODY_TYPE"PLUMBING"
HDL_TAP"TRUE";
"B \NAC \NWC"2;
"S \NAC"
BN"2"124;
%"TAP"
"1","(-3325,4150)","0","mstr_standard","I197";
;
CDS_LIB"mstr_standard"
BODY_TYPE"PLUMBING"
HDL_TAP"TRUE";
"B \NAC \NWC"2;
"S \NAC"
BN"4"122;
%"TAP"
"1","(-3325,4200)","0","mstr_standard","I198";
;
CDS_LIB"mstr_standard"
BODY_TYPE"PLUMBING"
HDL_TAP"TRUE";
"B \NAC \NWC"2;
"S \NAC"
BN"3"123;
%"TAP"
"1","(-3325,4100)","0","mstr_standard","I199";
;
CDS_LIB"mstr_standard"
BODY_TYPE"PLUMBING"
HDL_TAP"TRUE";
"B \NAC \NWC"2;
"S \NAC"
BN"5"121;
%"TAP"
"1","(-3325,4000)","0","mstr_standard","I202";
;
CDS_LIB"mstr_standard"
BODY_TYPE"PLUMBING"
HDL_TAP"TRUE";
"B \NAC \NWC"2;
"S \NAC"
BN"7"119;
%"TAP"
"1","(-3325,4050)","0","mstr_standard","I203";
;
CDS_LIB"mstr_standard"
BODY_TYPE"PLUMBING"
HDL_TAP"TRUE";
"B \NAC \NWC"2;
"S \NAC"
BN"6"103;
%"TAP"
"1","(-3325,3850)","0","mstr_standard","I204";
;
CDS_LIB"mstr_standard"
BODY_TYPE"PLUMBING"
HDL_TAP"TRUE";
"B \NAC \NWC"2;
"S \NAC"
BN"9"117;
%"TAP"
"1","(-3325,3900)","0","mstr_standard","I205";
;
CDS_LIB"mstr_standard"
BODY_TYPE"PLUMBING"
HDL_TAP"TRUE";
"B \NAC \NWC"2;
"S \NAC"
BN"8"118;
%"TAP"
"1","(-3325,3800)","0","mstr_standard","I206";
;
CDS_LIB"mstr_standard"
BODY_TYPE"PLUMBING"
HDL_TAP"TRUE";
"B \NAC \NWC"2;
"S \NAC"
BN"10"114;
%"TAP"
"1","(-3325,3750)","0","mstr_standard","I207";
;
CDS_LIB"mstr_standard"
BODY_TYPE"PLUMBING"
HDL_TAP"TRUE";
"B \NAC \NWC"2;
"S \NAC"
BN"11"112;
%"TAP"
"1","(-3325,3600)","0","mstr_standard","I208";
;
CDS_LIB"mstr_standard"
BODY_TYPE"PLUMBING"
HDL_TAP"TRUE";
"B \NAC \NWC"2;
"S \NAC"
BN"14"108;
%"TAP"
"1","(-3325,3700)","0","mstr_standard","I209";
;
CDS_LIB"mstr_standard"
BODY_TYPE"PLUMBING"
HDL_TAP"TRUE";
"B \NAC \NWC"2;
"S \NAC"
BN"12"110;
%"TAP"
"1","(-3325,3650)","0","mstr_standard","I210";
;
CDS_LIB"mstr_standard"
BODY_TYPE"PLUMBING"
HDL_TAP"TRUE";
"B \NAC \NWC"2;
"S \NAC"
BN"13"109;
%"TAP"
"1","(-3325,3550)","0","mstr_standard","I211";
;
CDS_LIB"mstr_standard"
BODY_TYPE"PLUMBING"
HDL_TAP"TRUE";
"B \NAC \NWC"2;
"S \NAC"
BN"15"107;
%"TAP"
"1","(-3325,3450)","0","mstr_standard","I212";
;
CDS_LIB"mstr_standard"
BODY_TYPE"PLUMBING"
HDL_TAP"TRUE";
"B \NAC \NWC"2;
"S \NAC"
BN"16"106;
%"TAP"
"1","(-3325,3400)","0","mstr_standard","I213";
;
CDS_LIB"mstr_standard"
BODY_TYPE"PLUMBING"
HDL_TAP"TRUE";
"B \NAC \NWC"2;
"S \NAC"
BN"17"105;
%"TAP"
"1","(-3325,3350)","0","mstr_standard","I214";
;
CDS_LIB"mstr_standard"
BODY_TYPE"PLUMBING"
HDL_TAP"TRUE";
"B \NAC \NWC"2;
"S \NAC"
BN"18"104;
%"TAP"
"1","(-3325,3250)","0","mstr_standard","I215";
;
CDS_LIB"mstr_standard"
BODY_TYPE"PLUMBING"
HDL_TAP"TRUE";
"B \NAC \NWC"2;
"S \NAC"
BN"20"116;
%"TAP"
"1","(-3325,3300)","0","mstr_standard","I216";
;
CDS_LIB"mstr_standard"
BODY_TYPE"PLUMBING"
HDL_TAP"TRUE";
"B \NAC \NWC"2;
"S \NAC"
BN"19"120;
%"TAP"
"1","(-3325,3200)","0","mstr_standard","I217";
;
CDS_LIB"mstr_standard"
BODY_TYPE"PLUMBING"
HDL_TAP"TRUE";
"B \NAC \NWC"2;
"S \NAC"
BN"21"115;
%"TAP"
"1","(-3325,3100)","0","mstr_standard","I218";
;
CDS_LIB"mstr_standard"
BODY_TYPE"PLUMBING"
HDL_TAP"TRUE";
"B \NAC \NWC"2;
"S \NAC"
BN"23"111;
%"TAP"
"1","(-3325,3150)","0","mstr_standard","I219";
;
CDS_LIB"mstr_standard"
BODY_TYPE"PLUMBING"
HDL_TAP"TRUE";
"B \NAC \NWC"2;
"S \NAC"
BN"22"113;
%"TAP"
"1","(-3325,3000)","0","mstr_standard","I220";
;
CDS_LIB"mstr_standard"
BODY_TYPE"PLUMBING"
HDL_TAP"TRUE";
"B \NAC \NWC"2;
"S \NAC"
BN"24"90;
%"TAP"
"1","(-3325,2950)","0","mstr_standard","I221";
;
CDS_LIB"mstr_standard"
BODY_TYPE"PLUMBING"
HDL_TAP"TRUE";
"B \NAC \NWC"2;
"S \NAC"
BN"25"89;
%"TAP"
"1","(-3325,2850)","0","mstr_standard","I222";
;
CDS_LIB"mstr_standard"
BODY_TYPE"PLUMBING"
HDL_TAP"TRUE";
"B \NAC \NWC"2;
"S \NAC"
BN"27"87;
%"TAP"
"1","(-3325,2900)","0","mstr_standard","I223";
;
CDS_LIB"mstr_standard"
BODY_TYPE"PLUMBING"
HDL_TAP"TRUE";
"B \NAC \NWC"2;
"S \NAC"
BN"26"88;
%"TAP"
"1","(-3325,2750)","0","mstr_standard","I224";
;
CDS_LIB"mstr_standard"
BODY_TYPE"PLUMBING"
HDL_TAP"TRUE";
"B \NAC \NWC"2;
"S \NAC"
BN"29"85;
%"TAP"
"1","(-3325,2800)","0","mstr_standard","I225";
;
CDS_LIB"mstr_standard"
BODY_TYPE"PLUMBING"
HDL_TAP"TRUE";
"B \NAC \NWC"2;
"S \NAC"
BN"28"86;
%"TAP"
"1","(-3325,2700)","0","mstr_standard","I226";
;
CDS_LIB"mstr_standard"
BODY_TYPE"PLUMBING"
HDL_TAP"TRUE";
"B \NAC \NWC"2;
"S \NAC"
BN"30"97;
%"TAP"
"1","(-3325,2650)","0","mstr_standard","I227";
;
CDS_LIB"mstr_standard"
BODY_TYPE"PLUMBING"
HDL_TAP"TRUE";
"B \NAC \NWC"2;
"S \NAC"
BN"31"95;
%"TAP"
"1","(-3325,2500)","0","mstr_standard","I228";
;
CDS_LIB"mstr_standard"
BODY_TYPE"PLUMBING"
HDL_TAP"TRUE";
"B \NAC \NWC"3;
"S \NAC"
BN"1"101;
%"TAP"
"1","(-3325,2450)","0","mstr_standard","I229";
;
CDS_LIB"mstr_standard"
BODY_TYPE"PLUMBING"
HDL_TAP"TRUE";
"B \NAC \NWC"3;
"S \NAC"
BN"2"100;
%"TAP"
"1","(-3325,2550)","0","mstr_standard","I230";
;
CDS_LIB"mstr_standard"
BODY_TYPE"PLUMBING"
HDL_TAP"TRUE";
"B \NAC \NWC"3;
"S \NAC"
BN"0"102;
%"TAP"
"1","(-3325,2400)","0","mstr_standard","I231";
;
CDS_LIB"mstr_standard"
BODY_TYPE"PLUMBING"
HDL_TAP"TRUE";
"B \NAC \NWC"3;
"S \NAC"
BN"3"99;
%"TAP"
"1","(-3325,2350)","0","mstr_standard","I232";
;
CDS_LIB"mstr_standard"
BODY_TYPE"PLUMBING"
HDL_TAP"TRUE";
"B \NAC \NWC"3;
"S \NAC"
BN"4"98;
%"TAP"
"1","(-3325,2200)","0","mstr_standard","I233";
;
CDS_LIB"mstr_standard"
BODY_TYPE"PLUMBING"
HDL_TAP"TRUE";
"B \NAC \NWC"3;
"S \NAC"
BN"7"91;
%"TAP"
"1","(-3325,2300)","0","mstr_standard","I234";
;
CDS_LIB"mstr_standard"
BODY_TYPE"PLUMBING"
HDL_TAP"TRUE";
"B \NAC \NWC"3;
"S \NAC"
BN"5"96;
%"TAP"
"1","(-3325,2250)","0","mstr_standard","I235";
;
CDS_LIB"mstr_standard"
BODY_TYPE"PLUMBING"
HDL_TAP"TRUE";
"B \NAC \NWC"3;
"S \NAC"
BN"6"93;
%"TAP"
"1","(-3325,2050)","0","mstr_standard","I236";
;
CDS_LIB"mstr_standard"
BODY_TYPE"PLUMBING"
HDL_TAP"TRUE";
"B \NAC \NWC"4;
"S \NAC"
BN"1"92;
%"TAP"
"1","(-3325,2100)","0","mstr_standard","I237";
;
CDS_LIB"mstr_standard"
BODY_TYPE"PLUMBING"
HDL_TAP"TRUE";
"B \NAC \NWC"4;
"S \NAC"
BN"0"94;
%"TAP"
"1","(-3325,2000)","0","mstr_standard","I238";
;
CDS_LIB"mstr_standard"
BODY_TYPE"PLUMBING"
HDL_TAP"TRUE";
"B \NAC \NWC"4;
"S \NAC"
BN"2"84;
%"TAP"
"1","(-3325,1950)","0","mstr_standard","I239";
;
CDS_LIB"mstr_standard"
BODY_TYPE"PLUMBING"
HDL_TAP"TRUE";
"B \NAC \NWC"4;
"S \NAC"
BN"3"83;
%"TAP"
"1","(-3325,1800)","0","mstr_standard","I240";
;
CDS_LIB"mstr_standard"
BODY_TYPE"PLUMBING"
HDL_TAP"TRUE";
"B \NAC \NWC"4;
"S \NAC"
BN"6"80;
%"TAP"
"1","(-3325,1900)","0","mstr_standard","I241";
;
CDS_LIB"mstr_standard"
BODY_TYPE"PLUMBING"
HDL_TAP"TRUE";
"B \NAC \NWC"4;
"S \NAC"
BN"4"82;
%"TAP"
"1","(-3325,1850)","0","mstr_standard","I242";
;
CDS_LIB"mstr_standard"
BODY_TYPE"PLUMBING"
HDL_TAP"TRUE";
"B \NAC \NWC"4;
"S \NAC"
BN"5"81;
%"TAP"
"1","(-3325,1750)","0","mstr_standard","I243";
;
CDS_LIB"mstr_standard"
BODY_TYPE"PLUMBING"
HDL_TAP"TRUE";
"B \NAC \NWC"4;
"S \NAC"
BN"7"79;
%"TAP"
"1","(-5750,6150)","2","mstr_standard","I244";
;
CDS_LIB"mstr_standard"
BODY_TYPE"PLUMBING"
HDL_TAP"TRUE";
"B \NAC \NWC"5;
"S \NAC"
BN"0"78;
%"TAP"
"1","(-5750,6050)","2","mstr_standard","I245";
;
CDS_LIB"mstr_standard"
BODY_TYPE"PLUMBING"
HDL_TAP"TRUE";
"B \NAC \NWC"5;
"S \NAC"
BN"1"69;
%"TAP"
"1","(-5750,5950)","2","mstr_standard","I246";
;
CDS_LIB"mstr_standard"
BODY_TYPE"PLUMBING"
HDL_TAP"TRUE";
"B \NAC \NWC"5;
"S \NAC"
BN"2"67;
%"TAP"
"1","(-5750,5850)","2","mstr_standard","I247";
;
CDS_LIB"mstr_standard"
BODY_TYPE"PLUMBING"
HDL_TAP"TRUE";
"B \NAC \NWC"5;
"S \NAC"
BN"3"65;
%"TAP"
"1","(-5750,5650)","2","mstr_standard","I248";
;
CDS_LIB"mstr_standard"
BODY_TYPE"PLUMBING"
HDL_TAP"TRUE";
"B \NAC \NWC"5;
"S \NAC"
BN"5"61;
%"TAP"
"1","(-5750,5750)","2","mstr_standard","I249";
;
CDS_LIB"mstr_standard"
BODY_TYPE"PLUMBING"
HDL_TAP"TRUE";
"B \NAC \NWC"5;
"S \NAC"
BN"4"63;
%"TAP"
"1","(-5950,6100)","2","mstr_standard","I250";
;
CDS_LIB"mstr_standard"
BODY_TYPE"PLUMBING"
HDL_TAP"TRUE";
"B \NAC \NWC"9;
"S \NAC"
BN"0"75;
%"TAP"
"1","(-5950,6000)","2","mstr_standard","I251";
;
CDS_LIB"mstr_standard"
BODY_TYPE"PLUMBING"
HDL_TAP"TRUE";
"B \NAC \NWC"9;
"S \NAC"
BN"1"74;
%"TAP"
"1","(-5950,5900)","2","mstr_standard","I252";
;
CDS_LIB"mstr_standard"
BODY_TYPE"PLUMBING"
HDL_TAP"TRUE";
"B \NAC \NWC"9;
"S \NAC"
BN"2"73;
%"TAP"
"1","(-5950,5800)","2","mstr_standard","I253";
;
CDS_LIB"mstr_standard"
BODY_TYPE"PLUMBING"
HDL_TAP"TRUE";
"B \NAC \NWC"9;
"S \NAC"
BN"3"72;
%"TAP"
"1","(-5950,5700)","2","mstr_standard","I254";
;
CDS_LIB"mstr_standard"
BODY_TYPE"PLUMBING"
HDL_TAP"TRUE";
"B \NAC \NWC"9;
"S \NAC"
BN"4"71;
%"TAP"
"1","(-5750,5550)","2","mstr_standard","I255";
;
CDS_LIB"mstr_standard"
BODY_TYPE"PLUMBING"
HDL_TAP"TRUE";
"B \NAC \NWC"5;
"S \NAC"
BN"6"60;
%"TAP"
"1","(-5750,5450)","2","mstr_standard","I256";
;
CDS_LIB"mstr_standard"
BODY_TYPE"PLUMBING"
HDL_TAP"TRUE";
"B \NAC \NWC"5;
"S \NAC"
BN"7"59;
%"TAP"
"1","(-5750,5250)","2","mstr_standard","I257";
;
CDS_LIB"mstr_standard"
BODY_TYPE"PLUMBING"
HDL_TAP"TRUE";
"B \NAC \NWC"5;
"S \NAC"
BN"9"76;
%"TAP"
"1","(-5750,5350)","2","mstr_standard","I258";
;
CDS_LIB"mstr_standard"
BODY_TYPE"PLUMBING"
HDL_TAP"TRUE";
"B \NAC \NWC"5;
"S \NAC"
BN"8"77;
%"TAP"
"1","(-5950,5600)","2","mstr_standard","I259";
;
CDS_LIB"mstr_standard"
BODY_TYPE"PLUMBING"
HDL_TAP"TRUE";
"B \NAC \NWC"9;
"S \NAC"
BN"5"70;
%"TAP"
"1","(-5950,5500)","2","mstr_standard","I260";
;
CDS_LIB"mstr_standard"
BODY_TYPE"PLUMBING"
HDL_TAP"TRUE";
"B \NAC \NWC"9;
"S \NAC"
BN"6"68;
%"TAP"
"1","(-5950,5400)","2","mstr_standard","I261";
;
CDS_LIB"mstr_standard"
BODY_TYPE"PLUMBING"
HDL_TAP"TRUE";
"B \NAC \NWC"9;
"S \NAC"
BN"7"66;
%"TAP"
"1","(-5950,5300)","2","mstr_standard","I262";
;
CDS_LIB"mstr_standard"
BODY_TYPE"PLUMBING"
HDL_TAP"TRUE";
"B \NAC \NWC"9;
"S \NAC"
BN"8"64;
%"TAP"
"1","(-5950,5200)","2","mstr_standard","I263";
;
CDS_LIB"mstr_standard"
BODY_TYPE"PLUMBING"
HDL_TAP"TRUE";
"B \NAC \NWC"9;
"S \NAC"
BN"9"62;
%"TAP"
"1","(-5750,5000)","2","mstr_standard","I264";
;
CDS_LIB"mstr_standard"
BODY_TYPE"PLUMBING"
HDL_TAP"TRUE";
"B \NAC \NWC"6;
"S \NAC"
BN"1"40;
%"TAP"
"1","(-5750,5100)","2","mstr_standard","I265";
;
CDS_LIB"mstr_standard"
BODY_TYPE"PLUMBING"
HDL_TAP"TRUE";
"B \NAC \NWC"6;
"S \NAC"
BN"0"42;
%"TAP"
"1","(-5750,4900)","2","mstr_standard","I266";
;
CDS_LIB"mstr_standard"
BODY_TYPE"PLUMBING"
HDL_TAP"TRUE";
"B \NAC \NWC"6;
"S \NAC"
BN"2"57;
%"TAP"
"1","(-5750,4800)","2","mstr_standard","I267";
;
CDS_LIB"mstr_standard"
BODY_TYPE"PLUMBING"
HDL_TAP"TRUE";
"B \NAC \NWC"6;
"S \NAC"
BN"3"55;
%"TAP"
"1","(-5750,4700)","2","mstr_standard","I268";
;
CDS_LIB"mstr_standard"
BODY_TYPE"PLUMBING"
HDL_TAP"TRUE";
"B \NAC \NWC"6;
"S \NAC"
BN"4"53;
%"TAP"
"1","(-5950,5050)","2","mstr_standard","I269";
;
CDS_LIB"mstr_standard"
BODY_TYPE"PLUMBING"
HDL_TAP"TRUE";
"B \NAC \NWC"10;
"S \NAC"
BN"0"47;
%"TAP"
"1","(-5950,4950)","2","mstr_standard","I270";
;
CDS_LIB"mstr_standard"
BODY_TYPE"PLUMBING"
HDL_TAP"TRUE";
"B \NAC \NWC"10;
"S \NAC"
BN"1"46;
%"TAP"
"1","(-5950,4850)","2","mstr_standard","I271";
;
CDS_LIB"mstr_standard"
BODY_TYPE"PLUMBING"
HDL_TAP"TRUE";
"B \NAC \NWC"10;
"S \NAC"
BN"2"45;
%"TAP"
"1","(-5950,4750)","2","mstr_standard","I272";
;
CDS_LIB"mstr_standard"
BODY_TYPE"PLUMBING"
HDL_TAP"TRUE";
"B \NAC \NWC"10;
"S \NAC"
BN"3"44;
%"TAP"
"1","(-5950,4650)","2","mstr_standard","I273";
;
CDS_LIB"mstr_standard"
BODY_TYPE"PLUMBING"
HDL_TAP"TRUE";
"B \NAC \NWC"10;
"S \NAC"
BN"4"43;
%"TAP"
"1","(-5750,4500)","2","mstr_standard","I274";
;
CDS_LIB"mstr_standard"
BODY_TYPE"PLUMBING"
HDL_TAP"TRUE";
"B \NAC \NWC"6;
"S \NAC"
BN"6"50;
%"TAP"
"1","(-5750,4600)","2","mstr_standard","I275";
;
CDS_LIB"mstr_standard"
BODY_TYPE"PLUMBING"
HDL_TAP"TRUE";
"B \NAC \NWC"6;
"S \NAC"
BN"5"51;
%"TAP"
"1","(-5750,4400)","2","mstr_standard","I276";
;
CDS_LIB"mstr_standard"
BODY_TYPE"PLUMBING"
HDL_TAP"TRUE";
"B \NAC \NWC"6;
"S \NAC"
BN"7"49;
%"TAP"
"1","(-5750,4300)","2","mstr_standard","I277";
;
CDS_LIB"mstr_standard"
BODY_TYPE"PLUMBING"
HDL_TAP"TRUE";
"B \NAC \NWC"6;
"S \NAC"
BN"8"48;
%"TAP"
"1","(-5750,4200)","2","mstr_standard","I278";
;
CDS_LIB"mstr_standard"
BODY_TYPE"PLUMBING"
HDL_TAP"TRUE";
"B \NAC \NWC"6;
"S \NAC"
BN"9"39;
%"TAP"
"1","(-5950,4550)","2","mstr_standard","I279";
;
CDS_LIB"mstr_standard"
BODY_TYPE"PLUMBING"
HDL_TAP"TRUE";
"B \NAC \NWC"10;
"S \NAC"
BN"5"41;
%"TAP"
"1","(-5950,4450)","2","mstr_standard","I280";
;
CDS_LIB"mstr_standard"
BODY_TYPE"PLUMBING"
HDL_TAP"TRUE";
"B \NAC \NWC"10;
"S \NAC"
BN"6"58;
%"TAP"
"1","(-5950,4350)","2","mstr_standard","I281";
;
CDS_LIB"mstr_standard"
BODY_TYPE"PLUMBING"
HDL_TAP"TRUE";
"B \NAC \NWC"10;
"S \NAC"
BN"7"56;
%"TAP"
"1","(-5950,4150)","2","mstr_standard","I282";
;
CDS_LIB"mstr_standard"
BODY_TYPE"PLUMBING"
HDL_TAP"TRUE";
"B \NAC \NWC"10;
"S \NAC"
BN"9"52;
%"TAP"
"1","(-5950,4250)","2","mstr_standard","I283";
;
CDS_LIB"mstr_standard"
BODY_TYPE"PLUMBING"
HDL_TAP"TRUE";
"B \NAC \NWC"10;
"S \NAC"
BN"8"54;
%"TAP"
"1","(-5950,3950)","2","mstr_standard","I288";
;
CDS_LIB"mstr_standard"
BODY_TYPE"PLUMBING"
HDL_TAP"TRUE";
"B \NAC \NWC"7;
"S \NAC"
BN"1"36;
%"TAP"
"1","(-5950,4000)","2","mstr_standard","I289";
;
CDS_LIB"mstr_standard"
BODY_TYPE"PLUMBING"
HDL_TAP"TRUE";
"B \NAC \NWC"7;
"S \NAC"
BN"0"38;
%"TAP"
"1","(-5950,3900)","2","mstr_standard","I290";
;
CDS_LIB"mstr_standard"
BODY_TYPE"PLUMBING"
HDL_TAP"TRUE";
"B \NAC \NWC"7;
"S \NAC"
BN"2"34;
%"TAP"
"1","(-5950,3850)","2","mstr_standard","I291";
;
CDS_LIB"mstr_standard"
BODY_TYPE"PLUMBING"
HDL_TAP"TRUE";
"B \NAC \NWC"7;
"S \NAC"
BN"3"32;
%"TAP"
"1","(-5950,3800)","2","mstr_standard","I292";
;
CDS_LIB"mstr_standard"
BODY_TYPE"PLUMBING"
HDL_TAP"TRUE";
"B \NAC \NWC"7;
"S \NAC"
BN"4"30;
%"TAP"
"1","(-5950,3750)","2","mstr_standard","I293";
;
CDS_LIB"mstr_standard"
BODY_TYPE"PLUMBING"
HDL_TAP"TRUE";
"B \NAC \NWC"7;
"S \NAC"
BN"5"28;
%"TAP"
"1","(-5950,3700)","2","mstr_standard","I294";
;
CDS_LIB"mstr_standard"
BODY_TYPE"PLUMBING"
HDL_TAP"TRUE";
"B \NAC \NWC"7;
"S \NAC"
BN"6"26;
%"TAP"
"1","(-5950,3600)","2","mstr_standard","I295";
;
CDS_LIB"mstr_standard"
BODY_TYPE"PLUMBING"
HDL_TAP"TRUE";
"B \NAC \NWC"8;
"S \NAC"
BN"0"37;
%"TAP"
"1","(-5950,3500)","2","mstr_standard","I296";
;
CDS_LIB"mstr_standard"
BODY_TYPE"PLUMBING"
HDL_TAP"TRUE";
"B \NAC \NWC"8;
"S \NAC"
BN"2"33;
%"TAP"
"1","(-5950,3550)","2","mstr_standard","I297";
;
CDS_LIB"mstr_standard"
BODY_TYPE"PLUMBING"
HDL_TAP"TRUE";
"B \NAC \NWC"8;
"S \NAC"
BN"1"35;
%"TAP"
"1","(-5950,3450)","2","mstr_standard","I298";
;
CDS_LIB"mstr_standard"
BODY_TYPE"PLUMBING"
HDL_TAP"TRUE";
"B \NAC \NWC"8;
"S \NAC"
BN"3"31;
%"TAP"
"1","(-5950,3400)","2","mstr_standard","I299";
;
CDS_LIB"mstr_standard"
BODY_TYPE"PLUMBING"
HDL_TAP"TRUE";
"B \NAC \NWC"8;
"S \NAC"
BN"4"29;
%"TAP"
"1","(-5950,3350)","2","mstr_standard","I300";
;
CDS_LIB"mstr_standard"
BODY_TYPE"PLUMBING"
HDL_TAP"TRUE";
"B \NAC \NWC"8;
"S \NAC"
BN"5"27;
%"TAP"
"1","(-5950,3300)","2","mstr_standard","I301";
;
CDS_LIB"mstr_standard"
BODY_TYPE"PLUMBING"
HDL_TAP"TRUE";
"B \NAC \NWC"8;
"S \NAC"
BN"6"25;
%"Q_RES"
"1","(-6625,2300)","0","pure_quanta","I314";
;
LOCATION"R505"
$SEC"1"
CDS_SEC"1"
TOLERANCE"1%"
VALUE"15   "
PART_NUMBER"CS01502FB11"
PACK_TYPE"0402LF"
CDS_LIB"pure_quanta"
WATTAGE"1/16W"
MATERIAL"CHIP";
"B"
$PN"2"13;
"A"
$PN"1"11;
END.
